(kicad_pcb
	(version 20260206)
	(generator "pcbnew")
	(generator_version "10.0")
	(general
		(thickness 1.6)
		(legacy_teardrops no)
	)
	(paper "A4")
	(title_block
		(title "Bryce Canyon_F.DPB_16315-1-OCP.brd")
		(comment 1 "Bryce Canyon / footprints 1759-1763 of 2223")
	)
	(layers
		(0 "F.Cu" signal "TOP")
		(4 "In1.Cu" signal "L2GND")
		(6 "In2.Cu" signal "L3")
		(8 "In3.Cu" signal "L4GND")
		(10 "In4.Cu" signal "L5")
		(12 "In5.Cu" signal "L6VCC")
		(14 "In6.Cu" signal "L7VCC")
		(16 "In7.Cu" signal "L8")
		(18 "In8.Cu" signal "L9GND")
		(20 "In9.Cu" signal "L10")
		(22 "In10.Cu" signal "L11GND")
		(2 "B.Cu" signal "BOTTOM")
		(9 "F.Adhes" user "F.Adhesive")
		(11 "B.Adhes" user "B.Adhesive")
		(13 "F.Paste" user "Package Geometry/Pastemask Top")
		(15 "B.Paste" user "Package Geometry/Pastemask Bottom")
		(5 "F.SilkS" user "Ref Des/Silkscreen Top")
		(7 "B.SilkS" user "Ref Des/Silkscreen Bottom")
		(1 "F.Mask" user "Board Geometry/Soldermask Top")
		(3 "B.Mask" user "Board Geometry/Soldermask Bottom")
		(17 "Dwgs.User" user "User.Drawings")
		(19 "Cmts.User" user "User.Comments")
		(21 "Eco1.User" user "User.Eco1")
		(23 "Eco2.User" user "User.Eco2")
		(25 "Edge.Cuts" user "Board Geometry/Outline")
		(27 "Margin" user)
		(31 "F.CrtYd" user "Package Geometry/Place Bound Top")
		(29 "B.CrtYd" user "Package Geometry/Place Bound Bottom")
		(35 "F.Fab" user "Ref Des/Assembly Top")
		(33 "B.Fab" user "Ref Des/Assembly Bottom")
	)
	(footprint ""
		(layer "F.Cu")
		(at 86.085934 -25.04821)
		(property "Reference" "U17"
			(at 0 0 0)
			(layer "F.SilkS")
			(hide yes)
			(effects
				(font
					(size 1.27 1.27)
				)
			)
		)
		(property "Value" "TCA9555PWR-GP"
			(at 0 -6.9342 0)
			(unlocked yes)
			(layer "F.Fab")
			(hide yes)
			(effects
				(font
					(size 1.016 1.016)
					(thickness 0.1524)
				)
			)
		)
		(property "Device Type" "TSOIC24H48"
			(at 0 -8.5852 0)
			(unlocked yes)
			(layer "F.Fab")
			(hide yes)
			(effects
				(font
					(size 1.016 1.016)
					(thickness 0.1524)
				)
			)
		)
		(duplicate_pad_numbers_are_jumpers no)
		(fp_line
			(start -4.2291 -1.397)
			(end 3.81 -1.397)
			(stroke
				(width 0.1524)
				(type default)
			)
			(layer "F.SilkS")
		)
		(fp_line
			(start -4.2291 -0.8001)
			(end -3.429 0)
			(stroke
				(width 0.1524)
				(type default)
			)
			(layer "F.SilkS")
		)
		(fp_line
			(start -4.2291 3.937)
			(end -4.2291 -1.397)
			(stroke
				(width 0.1524)
				(type default)
			)
			(layer "F.SilkS")
		)
		(fp_line
			(start -4.22656 3.81)
			(end -4.2291 1.397)
			(stroke
				(width 0.508)
				(type default)
			)
			(layer "F.SilkS")
		)
		(fp_line
			(start -3.429 0)
			(end -4.2291 0.8001)
			(stroke
				(width 0.1524)
				(type default)
			)
			(layer "F.SilkS")
		)
		(fp_line
			(start 3.81 -1.397)
			(end 3.81 1.397)
			(stroke
				(width 0.1524)
				(type default)
			)
			(layer "F.SilkS")
		)
		(fp_line
			(start 3.81 1.397)
			(end -4.2291 1.397)
			(stroke
				(width 0.1524)
				(type default)
			)
			(layer "F.SilkS")
		)
		(fp_poly
			(pts
				(xy -3.90652 -1.8542) (xy 3.90652 -1.8542) (xy 3.90652 1.8542) (xy -3.90652 1.8542)
			)
			(stroke
				(width 0)
				(type default)
			)
			(fill yes)
			(layer "F.SilkS")
		)
		(fp_poly
			(pts
				(xy -4.2164 3.81) (xy 4.2164 3.81) (xy 4.22656 -3.81) (xy -4.2164 -3.81)
			)
			(stroke
				(width 0)
				(type default)
			)
			(fill no)
			(layer "F.CrtYd")
		)
		(fp_poly
			(pts
				(xy -4.22656 -3.81) (xy 4.22656 -3.81) (xy 4.22656 3.81) (xy -4.22656 3.81)
			)
			(stroke
				(width 0)
				(type default)
			)
			(fill no)
			(layer "F.Fab")
		)
		(pad "1" smd rect
			(at -3.57632 2.8194)
			(size 0.3556 1.524)
			(layers "F.Cu" "F.Mask" "F.Paste")
			(net "BMC_A_MISC_ALERT_N")
		)
		(pad "2" smd rect
			(at -2.92608 2.8194)
			(size 0.3556 1.524)
			(layers "F.Cu" "F.Mask" "F.Paste")
			(net "IO_EXP10_A1")
		)
		(pad "3" smd rect
			(at -2.27584 2.8194)
			(size 0.3556 1.524)
			(layers "F.Cu" "F.Mask" "F.Paste")
			(net "IO_EXP10_A2")
		)
		(pad "4" smd rect
			(at -1.6256 2.8194)
			(size 0.3556 1.524)
			(layers "F.Cu" "F.Mask" "F.Paste")
			(net "COMP_A_INS_N")
		)
		(pad "5" smd rect
			(at -0.97536 2.8194)
			(size 0.3556 1.524)
			(layers "F.Cu" "F.Mask" "F.Paste")
			(net "FAN_0_INS_N")
		)
		(pad "6" smd rect
			(at -0.32512 2.8194)
			(size 0.3556 1.524)
			(layers "F.Cu" "F.Mask" "F.Paste")
			(net "FAN_1_INS_N")
		)
		(pad "7" smd rect
			(at 0.32512 2.8194)
			(size 0.3556 1.524)
			(layers "F.Cu" "F.Mask" "F.Paste")
			(net "FAN_2_INS_N")
		)
		(pad "8" smd rect
			(at 0.97536 2.8194)
			(size 0.3556 1.524)
			(layers "F.Cu" "F.Mask" "F.Paste")
			(net "FAN_3_INS_N")
		)
		(pad "9" smd rect
			(at 1.6256 2.8194)
			(size 0.3556 1.524)
			(layers "F.Cu" "F.Mask" "F.Paste")
			(net "IOM_B_INS_N")
		)
		(pad "10" smd rect
			(at 2.27584 2.8194)
			(size 0.3556 1.524)
			(layers "F.Cu" "F.Mask" "F.Paste")
			(net "SCC_A_INS_N")
		)
		(pad "11" smd rect
			(at 2.92608 2.8194)
			(size 0.3556 1.524)
			(layers "F.Cu" "F.Mask" "F.Paste")
			(net "SCC_B_INS_N")
		)
		(pad "12" smd rect
			(at 3.57632 2.8194)
			(size 0.3556 1.524)
			(layers "F.Cu" "F.Mask" "F.Paste")
			(net "GND")
		)
		(pad "13" smd rect
			(at 3.57632 -2.8194)
			(size 0.3556 1.524)
			(layers "F.Cu" "F.Mask" "F.Paste")
			(net "SCC_A_TYPE_0")
		)
		(pad "14" smd rect
			(at 2.92608 -2.8194)
			(size 0.3556 1.524)
			(layers "F.Cu" "F.Mask" "F.Paste")
			(net "SCC_A_TYPE_1")
		)
		(pad "15" smd rect
			(at 2.27584 -2.8194)
			(size 0.3556 1.524)
			(layers "F.Cu" "F.Mask" "F.Paste")
			(net "SCC_A_TYPE_2")
		)
		(pad "16" smd rect
			(at 1.6256 -2.8194)
			(size 0.3556 1.524)
			(layers "F.Cu" "F.Mask" "F.Paste")
			(net "SCC_A_TYPE_3")
		)
		(pad "17" smd rect
			(at 0.97536 -2.8194)
			(size 0.3556 1.524)
			(layers "F.Cu" "F.Mask" "F.Paste")
			(net "SCC_A_STBY_PGOOD")
		)
		(pad "18" smd rect
			(at 0.32512 -2.8194)
			(size 0.3556 1.524)
			(layers "F.Cu" "F.Mask" "F.Paste")
			(net "SCC_A_FULL_PGOOD")
		)
		(pad "19" smd rect
			(at -0.32512 -2.8194)
			(size 0.3556 1.524)
			(layers "F.Cu" "F.Mask" "F.Paste")
			(net "COMP_A_PGOOD")
		)
		(pad "20" smd rect
			(at -0.97536 -2.8194)
			(size 0.3556 1.524)
			(layers "F.Cu" "F.Mask" "F.Paste")
			(net "DRAWER_CLOSED_N")
		)
		(pad "21" smd rect
			(at -1.6256 -2.8194)
			(size 0.3556 1.524)
			(layers "F.Cu" "F.Mask" "F.Paste")
			(net "IO_EXP10_A0")
		)
		(pad "22" smd rect
			(at -2.27584 -2.8194)
			(size 0.3556 1.524)
			(layers "F.Cu" "F.Mask" "F.Paste")
			(net "IO_EXP10_SCL")
		)
		(pad "23" smd rect
			(at -2.92608 -2.8194)
			(size 0.3556 1.524)
			(layers "F.Cu" "F.Mask" "F.Paste")
			(net "IO_EXP10_SDA")
		)
		(pad "24" smd rect
			(at -3.57632 -2.8194)
			(size 0.3556 1.524)
			(layers "F.Cu" "F.Mask" "F.Paste")
			(net "P3V3_STBY_A")
		)
	)
	(footprint ""
		(layer "F.Cu")
		(at 133.252718 -301.413164 90)
		(property "Reference" "R570"
			(at 0 0 90)
			(layer "F.SilkS")
			(hide yes)
			(effects
				(font
					(size 1.27 1.27)
				)
			)
		)
		(property "Value" "4K7R2J-2-GP"
			(at 0.064008 -3.993896 90)
			(unlocked yes)
			(layer "F.Fab")
			(hide yes)
			(effects
				(font
					(size 1.016 1.016)
					(thickness 0.1524)
				)
			)
		)
		(property "Device Type" "R402H16"
			(at 0.064008 -5.517896 90)
			(unlocked yes)
			(layer "F.Fab")
			(hide yes)
			(effects
				(font
					(size 1.016 1.016)
					(thickness 0.1524)
				)
			)
		)
		(duplicate_pad_numbers_are_jumpers no)
		(fp_line
			(start 0.508 -0.9398)
			(end -0.508 -0.9398)
			(stroke
				(width 0.1524)
				(type default)
			)
			(layer "F.SilkS")
		)
		(fp_line
			(start -0.508 -0.9398)
			(end -0.508 0.9398)
			(stroke
				(width 0.1524)
				(type default)
			)
			(layer "F.SilkS")
		)
		(fp_rect
			(start -0.508 0.9398)
			(end 0.508 -0.9398)
			(stroke
				(width 0)
				(type default)
			)
			(fill no)
			(layer "F.CrtYd")
		)
		(fp_rect
			(start -0.508 0.9398)
			(end 0.508 -0.9398)
			(stroke
				(width 0)
				(type default)
			)
			(fill no)
			(layer "F.Fab")
		)
		(pad "1" smd custom
			(at 0 -0.4445 90)
			(size 0.1397 0.1397)
			(layers "F.Cu" "F.Mask" "F.Paste")
			(net "DRIVE_B_28_FLT_LED")
			(options
				(clearance outline)
				(anchor circle)
			)
			(primitives
				(gr_poly
					(pts
						(arc
							(start -0.1778 -0.2794)
							(mid -0.249642 -0.249642)
							(end -0.2794 -0.1778)
						)
						(arc
							(start -0.2794 0.1778)
							(mid -0.249642 0.249642)
							(end -0.1778 0.2794)
						)
						(arc
							(start 0.1778 0.2794)
							(mid 0.249642 0.249642)
							(end 0.2794 0.1778)
						)
						(arc
							(start 0.2794 -0.1778)
							(mid 0.249642 -0.249642)
							(end 0.1778 -0.2794)
						)
					)
					(width 0)
					(fill yes)
				)
			)
		)
		(pad "2" smd custom
			(at 0 0.4445 90)
			(size 0.1397 0.1397)
			(layers "F.Cu" "F.Mask" "F.Paste")
			(net "GND")
			(options
				(clearance outline)
				(anchor circle)
			)
			(primitives
				(gr_poly
					(pts
						(arc
							(start -0.1778 -0.2794)
							(mid -0.249642 -0.249642)
							(end -0.2794 -0.1778)
						)
						(arc
							(start -0.2794 0.1778)
							(mid -0.249642 0.249642)
							(end -0.1778 0.2794)
						)
						(arc
							(start 0.1778 0.2794)
							(mid 0.249642 0.249642)
							(end 0.2794 0.1778)
						)
						(arc
							(start 0.2794 -0.1778)
							(mid 0.249642 -0.249642)
							(end 0.1778 -0.2794)
						)
					)
					(width 0)
					(fill yes)
				)
			)
		)
	)
	(footprint ""
		(layer "F.Cu")
		(at 426.120052 -61.127894 -90)
		(property "Reference" "R888"
			(at 0 0 270)
			(layer "F.SilkS")
			(hide yes)
			(effects
				(font
					(size 1.27 1.27)
				)
			)
		)
		(property "Value" "2R6F-GP"
			(at -0.0508 -4.8514 270)
			(unlocked yes)
			(layer "F.Fab")
			(hide yes)
			(effects
				(font
					(size 1.016 1.016)
					(thickness 0.1524)
				)
			)
		)
		(property "Device Type" "R1206H26"
			(at 0 -6.3754 270)
			(unlocked yes)
			(layer "F.Fab")
			(hide yes)
			(effects
				(font
					(size 1.016 1.016)
					(thickness 0.1524)
				)
			)
		)
		(duplicate_pad_numbers_are_jumpers no)
		(fp_line
			(start -1.016 2.2352)
			(end -1.016 -2.2352)
			(stroke
				(width 0.1524)
				(type default)
			)
			(layer "F.SilkS")
		)
		(fp_line
			(start 1.016 2.2352)
			(end -1.016 2.2352)
			(stroke
				(width 0.1524)
				(type default)
			)
			(layer "F.SilkS")
		)
		(fp_line
			(start -1.016 -2.2352)
			(end 1.016 -2.2352)
			(stroke
				(width 0.1524)
				(type default)
			)
			(layer "F.SilkS")
		)
		(fp_line
			(start 1.016 -2.2352)
			(end 1.016 2.2352)
			(stroke
				(width 0.1524)
				(type default)
			)
			(layer "F.SilkS")
		)
		(fp_rect
			(start -1.0922 2.3114)
			(end 1.0922 -2.3114)
			(stroke
				(width 0)
				(type default)
			)
			(fill no)
			(layer "F.CrtYd")
		)
		(fp_poly
			(pts
				(xy -1.0922 -2.3114) (xy 1.0922 -2.3114) (xy 1.0922 2.3114) (xy -1.0922 2.3114)
			)
			(stroke
				(width 0)
				(type default)
			)
			(fill no)
			(layer "F.Fab")
		)
		(pad "1" smd rect
			(at 0 -1.397 270)
			(size 1.651 1.27)
			(layers "F.Cu" "F.Mask" "F.Paste")
			(net "P5V_HDD33")
		)
		(pad "2" smd rect
			(at 0 1.397 270)
			(size 1.651 1.27)
			(layers "F.Cu" "F.Mask" "F.Paste")
			(net "5V_PRE_33")
		)
	)
	(footprint ""
		(layer "F.Cu")
		(at 174.0662 -284.473142 -90)
		(property "Reference" "R260"
			(at 0 0 270)
			(layer "F.SilkS")
			(hide yes)
			(effects
				(font
					(size 1.27 1.27)
				)
			)
		)
		(property "Value" "300KR2F-GP"
			(at 0.064008 -3.993896 270)
			(unlocked yes)
			(layer "F.Fab")
			(hide yes)
			(effects
				(font
					(size 1.016 1.016)
					(thickness 0.1524)
				)
			)
		)
		(property "Device Type" "R402H16"
			(at 0.064008 -5.517896 270)
			(unlocked yes)
			(layer "F.Fab")
			(hide yes)
			(effects
				(font
					(size 1.016 1.016)
					(thickness 0.1524)
				)
			)
		)
		(duplicate_pad_numbers_are_jumpers no)
		(fp_line
			(start -0.508 -0.9398)
			(end -0.508 0.9398)
			(stroke
				(width 0.1524)
				(type default)
			)
			(layer "F.SilkS")
		)
		(fp_line
			(start 0.508 -0.9398)
			(end -0.508 -0.9398)
			(stroke
				(width 0.1524)
				(type default)
			)
			(layer "F.SilkS")
		)
		(fp_rect
			(start -0.508 0.9398)
			(end 0.508 -0.9398)
			(stroke
				(width 0)
				(type default)
			)
			(fill no)
			(layer "F.CrtYd")
		)
		(fp_rect
			(start -0.508 0.9398)
			(end 0.508 -0.9398)
			(stroke
				(width 0)
				(type default)
			)
			(fill no)
			(layer "F.Fab")
		)
		(pad "1" smd custom
			(at 0 -0.4445 270)
			(size 0.1397 0.1397)
			(layers "F.Cu" "F.Mask" "F.Paste")
			(net "SW_HDD_N5")
			(options
				(clearance outline)
				(anchor circle)
			)
			(primitives
				(gr_poly
					(pts
						(arc
							(start -0.1778 -0.2794)
							(mid -0.249642 -0.249642)
							(end -0.2794 -0.1778)
						)
						(arc
							(start -0.2794 0.1778)
							(mid -0.249642 0.249642)
							(end -0.1778 0.2794)
						)
						(arc
							(start 0.1778 0.2794)
							(mid 0.249642 0.249642)
							(end 0.2794 0.1778)
						)
						(arc
							(start 0.2794 -0.1778)
							(mid 0.249642 -0.249642)
							(end 0.1778 -0.2794)
						)
					)
					(width 0)
					(fill yes)
				)
			)
		)
		(pad "2" smd custom
			(at 0 0.4445 270)
			(size 0.1397 0.1397)
			(layers "F.Cu" "F.Mask" "F.Paste")
			(net "P12V_A")
			(options
				(clearance outline)
				(anchor circle)
			)
			(primitives
				(gr_poly
					(pts
						(arc
							(start -0.1778 -0.2794)
							(mid -0.249642 -0.249642)
							(end -0.2794 -0.1778)
						)
						(arc
							(start -0.2794 0.1778)
							(mid -0.249642 0.249642)
							(end -0.1778 0.2794)
						)
						(arc
							(start 0.1778 0.2794)
							(mid 0.249642 0.249642)
							(end 0.2794 0.1778)
						)
						(arc
							(start 0.2794 -0.1778)
							(mid 0.249642 -0.249642)
							(end 0.1778 -0.2794)
						)
					)
					(width 0)
					(fill yes)
				)
			)
		)
	)
	(footprint ""
		(layer "F.Cu")
		(at 235.676694 -244.146578 180)
		(property "Reference" "R68"
			(at 0 0 180)
			(layer "F.SilkS")
			(hide yes)
			(effects
				(font
					(size 1.27 1.27)
				)
			)
		)
		(property "Value" "4K7R2F-GP"
			(at 0.064008 -3.993896 180)
			(unlocked yes)
			(layer "F.Fab")
			(hide yes)
			(effects
				(font
					(size 1.016 1.016)
					(thickness 0.1524)
				)
			)
		)
		(property "Device Type" "R402H16"
			(at 0.064008 -5.517896 180)
			(unlocked yes)
			(layer "F.Fab")
			(hide yes)
			(effects
				(font
					(size 1.016 1.016)
					(thickness 0.1524)
				)
			)
		)
		(duplicate_pad_numbers_are_jumpers no)
		(fp_line
			(start 0.508 -0.9398)
			(end -0.508 -0.9398)
			(stroke
				(width 0.1524)
				(type default)
			)
			(layer "F.SilkS")
		)
		(fp_line
			(start -0.508 -0.9398)
			(end -0.508 0.9398)
			(stroke
				(width 0.1524)
				(type default)
			)
			(layer "F.SilkS")
		)
		(fp_rect
			(start -0.508 0.9398)
			(end 0.508 -0.9398)
			(stroke
				(width 0)
				(type default)
			)
			(fill no)
			(layer "F.CrtYd")
		)
		(fp_rect
			(start -0.508 0.9398)
			(end 0.508 -0.9398)
			(stroke
				(width 0)
				(type default)
			)
			(fill no)
			(layer "F.Fab")
		)
		(pad "1" smd custom
			(at 0 -0.4445 180)
			(size 0.1397 0.1397)
			(layers "F.Cu" "F.Mask" "F.Paste")
			(net "IO_EXP1_A1")
			(options
				(clearance outline)
				(anchor circle)
			)
			(primitives
				(gr_poly
					(pts
						(arc
							(start -0.1778 -0.2794)
							(mid -0.249642 -0.249642)
							(end -0.2794 -0.1778)
						)
						(arc
							(start -0.2794 0.1778)
							(mid -0.249642 0.249642)
							(end -0.1778 0.2794)
						)
						(arc
							(start 0.1778 0.2794)
							(mid 0.249642 0.249642)
							(end 0.2794 0.1778)
						)
						(arc
							(start 0.2794 -0.1778)
							(mid 0.249642 -0.249642)
							(end 0.1778 -0.2794)
						)
					)
					(width 0)
					(fill yes)
				)
			)
		)
		(pad "2" smd custom
			(at 0 0.4445 180)
			(size 0.1397 0.1397)
			(layers "F.Cu" "F.Mask" "F.Paste")
			(net "GND")
			(options
				(clearance outline)
				(anchor circle)
			)
			(primitives
				(gr_poly
					(pts
						(arc
							(start -0.1778 -0.2794)
							(mid -0.249642 -0.249642)
							(end -0.2794 -0.1778)
						)
						(arc
							(start -0.2794 0.1778)
							(mid -0.249642 0.249642)
							(end -0.1778 0.2794)
						)
						(arc
							(start 0.1778 0.2794)
							(mid 0.249642 0.249642)
							(end 0.2794 0.1778)
						)
						(arc
							(start 0.2794 -0.1778)
							(mid 0.249642 -0.249642)
							(end 0.1778 -0.2794)
						)
					)
					(width 0)
					(fill yes)
				)
			)
		)
	)
)
